# BASEBOARD_FAB2 (Tioga Pass) — schematic netlist excerpt (pin names and nets, part order shuffled) for the footprints in the layout excerpt that follows; sources: Cadence DE-HDL packaged netlist, KiCad conversion of Wiwynn_Tioga_Pass_MB.brd

C5M11  CAP_A  47UF 4V 20% X5R  pkg 0603V  page 220 : A = PVDDQ_DEF ; B = GND
C3T3  CAPP  68UF 16V 20% TANT  pkg 3018  page 195 : A = P12V_STBY ; B = GND
C1M19  CAP  0.22UF 16V 10% X7R  pkg 0402  page 106 : A = P3E_CPU0_PE3_OCP_TXN<9> ; B = P3E_OCP_CPU0_PE3_C_TXN<9>

(kicad_pcb
	(version 20260206)
	(generator "pcbnew")
	(generator_version "10.0")
	(general
		(thickness 1.6)
		(legacy_teardrops no)
	)
	(paper "A4")
	(title_block
		(title "Wiwynn_Tioga_Pass_MB.brd")
		(comment 1 "Tioga Pass / footprints 3564-3566 of 4770")
	)
	(layers
		(0 "F.Cu" signal "TOP")
		(4 "In1.Cu" signal "L2GND")
		(6 "In2.Cu" signal "L3")
		(8 "In3.Cu" signal "L4GND")
		(10 "In4.Cu" signal "L5")
		(12 "In5.Cu" signal "L6GND")
		(14 "In6.Cu" signal "L7VCC")
		(16 "In7.Cu" signal "L8VCC")
		(18 "In8.Cu" signal "L9GND")
		(20 "In9.Cu" signal "L10")
		(22 "In10.Cu" signal "L11GND")
		(24 "In11.Cu" signal "L12")
		(26 "In12.Cu" signal "L13GND")
		(2 "B.Cu" signal "BOTTOM")
		(9 "F.Adhes" user "F.Adhesive")
		(11 "B.Adhes" user "B.Adhesive")
		(13 "F.Paste" user "Package Geometry/Pastemask Top")
		(15 "B.Paste" user "Package Geometry/Pastemask Bottom")
		(5 "F.SilkS" user "Ref Des/Silkscreen Top")
		(7 "B.SilkS" user "Ref Des/Silkscreen Bottom")
		(1 "F.Mask" user "Board Geometry/Soldermask Top")
		(3 "B.Mask" user "Board Geometry/Soldermask Bottom")
		(17 "Dwgs.User" user "User.Drawings")
		(19 "Cmts.User" user "User.Comments")
		(21 "Eco1.User" user "User.Eco1")
		(23 "Eco2.User" user "User.Eco2")
		(25 "Edge.Cuts" user "Board Geometry/Outline")
		(27 "Margin" user)
		(31 "F.CrtYd" user "Package Geometry/Place Bound Top")
		(29 "B.CrtYd" user "Package Geometry/Place Bound Bottom")
		(35 "F.Fab" user "Ref Des/Assembly Top")
		(33 "B.Fab" user "Ref Des/Assembly Bottom")
	)
	(footprint ""
		(layer "B.Cu")
		(at 446.024 -116.49202)
		(property "Reference" "C1M19"
			(at 0 0 0)
			(layer "B.SilkS")
			(hide yes)
			(effects
				(font
					(size 1.27 1.27)
				)
				(justify mirror)
			)
		)
		(property "Value" ""
			(at 0 0 0)
			(layer "B.Fab")
			(effects
				(font
					(size 1.27 1.27)
				)
				(justify mirror)
			)
		)
		(duplicate_pad_numbers_are_jumpers no)
		(fp_rect
			(start -0.3048 0.9906)
			(end 0.3048 -0.1016)
			(stroke
				(width 0)
				(type default)
			)
			(fill no)
			(layer "B.CrtYd")
		)
		(fp_line
			(start -0.3048 -0.1016)
			(end 0.3048 -0.1016)
			(stroke
				(width 0.1)
				(type default)
			)
			(layer "B.Fab")
		)
		(fp_line
			(start -0.3048 0.9906)
			(end -0.3048 -0.1016)
			(stroke
				(width 0.1)
				(type default)
			)
			(layer "B.Fab")
		)
		(fp_line
			(start 0.3048 -0.1016)
			(end 0.3048 0.9906)
			(stroke
				(width 0.1)
				(type default)
			)
			(layer "B.Fab")
		)
		(fp_line
			(start 0.3048 0.9906)
			(end -0.3048 0.9906)
			(stroke
				(width 0.1)
				(type default)
			)
			(layer "B.Fab")
		)
		(pad "1" smd rect
			(at 0 0 180)
			(size 0.508 0.508)
			(layers "B.Cu" "B.Mask" "B.Paste")
			(net "P3E_CPU0_PE3_OCP_TXN<9>")
		)
		(pad "2" smd rect
			(at 0 0.889 180)
			(size 0.508 0.508)
			(layers "B.Cu" "B.Mask" "B.Paste")
			(net "P3E_OCP_CPU0_PE3_C_TXN<9>")
		)
		(zone
			(layer "B.Cu")
			(hatch none 0.5)
			(connect_pads
				(clearance 0)
			)
			(min_thickness 0.25)
			(keepout
				(tracks allowed)
				(vias not_allowed)
				(pads allowed)
				(copperpour not_allowed)
				(footprints allowed)
			)
			(placement
				(enabled no)
				(sheetname "")
			)
			(fill
				(thermal_gap 0.5)
				(thermal_bridge_width 0.5)
				(island_removal_mode 0)
			)
			(polygon
				(pts
					(xy 445.77 -115.85702) (xy 446.278 -115.85702) (xy 446.278 -116.23802) (xy 445.77 -116.23802)
				)
			)
		)
		(zone
			(layer "B.Cu")
			(hatch none 0.5)
			(connect_pads
				(clearance 0)
			)
			(min_thickness 0.25)
			(keepout
				(tracks not_allowed)
				(vias allowed)
				(pads allowed)
				(copperpour not_allowed)
				(footprints allowed)
			)
			(placement
				(enabled no)
				(sheetname "")
			)
			(fill
				(thermal_gap 0.5)
				(thermal_bridge_width 0.5)
				(island_removal_mode 0)
			)
			(polygon
				(pts
					(xy 445.77 -115.85702) (xy 446.278 -115.85702) (xy 446.278 -116.23802) (xy 445.77 -116.23802)
				)
			)
		)
	)
	(footprint ""
		(layer "B.Cu")
		(at 245.815612 -125.55601 90)
		(property "Reference" "C5M11"
			(at 0 0 90)
			(layer "B.SilkS")
			(hide yes)
			(effects
				(font
					(size 1.27 1.27)
				)
				(justify mirror)
			)
		)
		(property "Value" ""
			(at 0 0 90)
			(layer "B.Fab")
			(effects
				(font
					(size 1.27 1.27)
				)
				(justify mirror)
			)
		)
		(duplicate_pad_numbers_are_jumpers no)
		(fp_rect
			(start 0.500126 1.598422)
			(end -0.500126 -0.201422)
			(stroke
				(width 0)
				(type default)
			)
			(fill no)
			(layer "B.CrtYd")
		)
		(fp_line
			(start 0.500126 -0.201422)
			(end -0.500126 -0.201422)
			(stroke
				(width 0.1)
				(type default)
			)
			(layer "B.Fab")
		)
		(fp_line
			(start -0.500126 -0.201422)
			(end -0.500126 1.598422)
			(stroke
				(width 0.1)
				(type default)
			)
			(layer "B.Fab")
		)
		(fp_line
			(start 0.500126 1.598422)
			(end 0.500126 -0.201422)
			(stroke
				(width 0.1)
				(type default)
			)
			(layer "B.Fab")
		)
		(fp_line
			(start -0.500126 1.598422)
			(end 0.500126 1.598422)
			(stroke
				(width 0.1)
				(type default)
			)
			(layer "B.Fab")
		)
		(pad "1" smd rect
			(at 0 0)
			(size 0.889 0.9906)
			(layers "B.Cu" "B.Mask" "B.Paste")
			(net "PVDDQ_DEF")
		)
		(pad "2" smd rect
			(at 0 1.397)
			(size 0.889 0.9906)
			(layers "B.Cu" "B.Mask" "B.Paste")
			(net "GND")
		)
		(zone
			(layer "B.Cu")
			(hatch none 0.5)
			(connect_pads
				(clearance 0)
			)
			(min_thickness 0.25)
			(keepout
				(tracks not_allowed)
				(vias allowed)
				(pads allowed)
				(copperpour not_allowed)
				(footprints allowed)
			)
			(placement
				(enabled no)
				(sheetname "")
			)
			(fill
				(thermal_gap 0.5)
				(thermal_bridge_width 0.5)
				(island_removal_mode 0)
			)
			(polygon
				(pts
					(xy 246.768112 -126.05131) (xy 246.260112 -126.05131) (xy 246.260112 -125.06071) (xy 246.768112 -125.06071)
				)
			)
		)
		(zone
			(layer "B.Cu")
			(hatch none 0.5)
			(connect_pads
				(clearance 0)
			)
			(min_thickness 0.25)
			(keepout
				(tracks allowed)
				(vias not_allowed)
				(pads allowed)
				(copperpour not_allowed)
				(footprints allowed)
			)
			(placement
				(enabled no)
				(sheetname "")
			)
			(fill
				(thermal_gap 0.5)
				(thermal_bridge_width 0.5)
				(island_removal_mode 0)
			)
			(polygon
				(pts
					(xy 246.768112 -126.05131) (xy 246.260112 -126.05131) (xy 246.260112 -125.06071) (xy 246.768112 -125.06071)
				)
			)
		)
	)
	(footprint ""
		(layer "B.Cu")
		(at 351.536 -34.798 -90)
		(property "Reference" "C3T3"
			(at 3.45567 5.207 0)
			(unlocked yes)
			(layer "B.SilkS")
			(effects
				(font
					(size 0.7874 0.5842)
					(thickness 0.1524)
				)
				(justify mirror)
			)
		)
		(property "Value" ""
			(at 0 0 90)
			(layer "B.Fab")
			(effects
				(font
					(size 1.27 1.27)
				)
				(justify mirror)
			)
		)
		(duplicate_pad_numbers_are_jumpers no)
		(fp_line
			(start -2.286 7.366)
			(end -1.600708 7.366)
			(stroke
				(width 0.1524)
				(type default)
			)
			(layer "B.SilkS")
		)
		(fp_line
			(start -2.286 7.366)
			(end -2.286 1.63195)
			(stroke
				(width 0.1524)
				(type default)
			)
			(layer "B.SilkS")
		)
		(fp_line
			(start 2.286 7.366)
			(end 1.60147 7.366)
			(stroke
				(width 0.1524)
				(type default)
			)
			(layer "B.SilkS")
		)
		(fp_line
			(start 2.286 7.366)
			(end 2.286 1.632712)
			(stroke
				(width 0.1524)
				(type default)
			)
			(layer "B.SilkS")
		)
		(fp_line
			(start -2.504948 1.633728)
			(end -1.6002 1.633728)
			(stroke
				(width 0.1524)
				(type default)
			)
			(layer "B.SilkS")
		)
		(fp_line
			(start 2.563114 1.633728)
			(end 1.6002 1.633728)
			(stroke
				(width 0.1524)
				(type default)
			)
			(layer "B.SilkS")
		)
		(fp_line
			(start -2.504948 -1.616456)
			(end -2.504948 1.633728)
			(stroke
				(width 0.1524)
				(type default)
			)
			(layer "B.SilkS")
		)
		(fp_line
			(start -1.6002 -1.616456)
			(end -2.504948 -1.616456)
			(stroke
				(width 0.1524)
				(type default)
			)
			(layer "B.SilkS")
		)
		(fp_line
			(start 1.6002 -1.616456)
			(end 2.563114 -1.616456)
			(stroke
				(width 0.1524)
				(type default)
			)
			(layer "B.SilkS")
		)
		(fp_line
			(start 2.563114 -1.616456)
			(end 2.563114 1.633728)
			(stroke
				(width 0.1524)
				(type default)
			)
			(layer "B.SilkS")
		)
		(fp_rect
			(start 2.286 7.366)
			(end -2.286 -0.254)
			(stroke
				(width 0)
				(type default)
			)
			(fill no)
			(layer "B.CrtYd")
		)
		(fp_line
			(start -2.286 7.366)
			(end 2.286 7.366)
			(stroke
				(width 0.1)
				(type default)
			)
			(layer "B.Fab")
		)
		(fp_line
			(start 2.286 7.366)
			(end 2.286 -0.254)
			(stroke
				(width 0.1)
				(type default)
			)
			(layer "B.Fab")
		)
		(fp_line
			(start -2.286 -0.254)
			(end -2.286 7.366)
			(stroke
				(width 0.1)
				(type default)
			)
			(layer "B.Fab")
		)
		(fp_line
			(start 2.286 -0.254)
			(end -2.286 -0.254)
			(stroke
				(width 0.1)
				(type default)
			)
			(layer "B.Fab")
		)
		(pad "1" smd rect
			(at 0 0 90)
			(size 2.54 3.048)
			(layers "B.Cu" "B.Mask" "B.Paste")
			(net "P12V_STBY")
		)
		(pad "2" smd rect
			(at 0 7.112 90)
			(size 2.54 3.048)
			(layers "B.Cu" "B.Mask" "B.Paste")
			(net "GND")
		)
	)
)
